FILE_TYPE = MACRO_DRAWING;
SET COLOR_WIRE YELLOW;
SET COLOR_PROP MONO;
SET COLOR_DOT WHITE;
SET COLOR_ARC YELLOW;
SET COLOR_BODY GREEN;
SET COLOR_NOTE MONO;
SET PROP_DISPLAY VALUE;
SET PAGE_NUMBER P115;
FORCEADD OFFPAGE..1
(-6300 2950);
FORCEPROP 2 LAST $XR0 ?
J 0
(-6552 2950);
DISPLAY 0.638298 (-6552 2950);
PAINT MONO (-6552 2950);
FORCEPROP 2 LAST $XRERR ?
J 0
(-6696 2950);
DISPLAY 0.638298 (-6696 2950);
PAINT MONO (-6696 2950);
DISPLAY INVISIBLE (-6696 2950);
FORCEPROP 2 LAST $XRERR ?
J 0
(-6696 2950);
DISPLAY 0.638298 (-6696 2950);
PAINT MONO (-6696 2950);
DISPLAY INVISIBLE (-6696 2950);
FORCEPROP 2 LAST $XRERR ?
J 0
(-6696 2950);
DISPLAY 0.638298 (-6696 2950);
PAINT MONO (-6696 2950);
DISPLAY INVISIBLE (-6696 2950);
FORCEPROP 2 LAST $XRERR ?
J 0
(-6696 2950);
DISPLAY 0.638298 (-6696 2950);
PAINT MONO (-6696 2950);
DISPLAY INVISIBLE (-6696 2950);
FORCEPROP 2 LAST $XRERR ?
J 0
(-6696 2950);
DISPLAY 0.638298 (-6696 2950);
PAINT MONO (-6696 2950);
DISPLAY INVISIBLE (-6696 2950);
FORCEPROP 2 LAST $XRERR ?
J 0
(-6696 2950);
DISPLAY 0.638298 (-6696 2950);
PAINT MONO (-6696 2950);
DISPLAY INVISIBLE (-6696 2950);
FORCEPROP 2 LAST $XRERR ?
J 0
(-6696 2950);
DISPLAY 0.638298 (-6696 2950);
PAINT MONO (-6696 2950);
DISPLAY INVISIBLE (-6696 2950);
FORCEPROP 2 LAST CDS_LIB mstr_standard
J 0
(-6300 2950);
PAINT ORANGE (-6300 2950);
DISPLAY INVISIBLE (-6300 2950);
FORCEPROP 1 LAST OFFPAGE TRUE
J 0
(-5975 2825);
DISPLAY 1.170213 (-5975 2825);
PAINT GREEN (-5975 2825);
DISPLAY INVISIBLE (-5975 2825);
FORCEPROP 1 LAST COMMENT_BODY TRUE
J 0
(-6175 2850);
DISPLAY 1.170213 (-6175 2850);
PAINT PEACH (-6175 2850);
DISPLAY INVISIBLE (-6175 2850);
FORCEPROP 2 LAST PATH I102
J 0
(-6550 3000);
DISPLAY 1.021277 (-6550 3000);
PAINT ORANGE (-6550 3000);
DISPLAY INVISIBLE (-6550 3000);
FORCEPROP 2 LAST $XRERR ?
J 0
(-6696 2950);
DISPLAY 0.638298 (-6696 2950);
PAINT MONO (-6696 2950);
DISPLAY INVISIBLE (-6696 2950);
FORCEPROP 2 LAST $XRERR ?
J 0
(-6696 2950);
DISPLAY 0.638298 (-6696 2950);
PAINT MONO (-6696 2950);
DISPLAY INVISIBLE (-6696 2950);
FORCEPROP 2 LAST $XRERR ?
J 0
(-6696 2950);
DISPLAY 0.638298 (-6696 2950);
PAINT MONO (-6696 2950);
DISPLAY INVISIBLE (-6696 2950);
FORCEPROP 2 LAST $XRERR ?
J 0
(-6696 2950);
DISPLAY 0.638298 (-6696 2950);
PAINT MONO (-6696 2950);
DISPLAY INVISIBLE (-6696 2950);
FORCEPROP 2 LAST $XRERR ?
J 0
(-6696 2950);
DISPLAY 0.638298 (-6696 2950);
PAINT MONO (-6696 2950);
DISPLAY INVISIBLE (-6696 2950);
FORCEPROP 2 LAST $XRERR ?
J 0
(-6696 2950);
DISPLAY 0.638298 (-6696 2950);
PAINT MONO (-6696 2950);
DISPLAY INVISIBLE (-6696 2950);
FORCEPROP 2 LAST $XRERR ?
J 0
(-6696 2950);
DISPLAY 0.638298 (-6696 2950);
PAINT MONO (-6696 2950);
DISPLAY INVISIBLE (-6696 2950);
FORCEPROP 2 LAST $XRERR UNIQUE?
J 0
(-6696 2950);
DISPLAY 0.638298 (-6696 2950);
PAINT MONO (-6696 2950);
DISPLAY INVISIBLE (-6696 2950);
FORCEADD OFFPAGE..1
(-6300 3000);
FORCEPROP 2 LAST $XR0 ?
J 0
(-6552 3000);
DISPLAY 0.638298 (-6552 3000);
PAINT MONO (-6552 3000);
FORCEPROP 2 LAST $XRERR ?
J 0
(-6696 3000);
DISPLAY 0.638298 (-6696 3000);
PAINT MONO (-6696 3000);
DISPLAY INVISIBLE (-6696 3000);
FORCEPROP 2 LAST $XRERR ?
J 0
(-6696 3000);
DISPLAY 0.638298 (-6696 3000);
PAINT MONO (-6696 3000);
DISPLAY INVISIBLE (-6696 3000);
FORCEPROP 2 LAST $XRERR ?
J 0
(-6696 3000);
DISPLAY 0.638298 (-6696 3000);
PAINT MONO (-6696 3000);
DISPLAY INVISIBLE (-6696 3000);
FORCEPROP 2 LAST $XRERR ?
J 0
(-6696 3000);
DISPLAY 0.638298 (-6696 3000);
PAINT MONO (-6696 3000);
DISPLAY INVISIBLE (-6696 3000);
FORCEPROP 2 LAST $XRERR ?
J 0
(-6696 3000);
DISPLAY 0.638298 (-6696 3000);
PAINT MONO (-6696 3000);
DISPLAY INVISIBLE (-6696 3000);
FORCEPROP 2 LAST $XRERR ?
J 0
(-6696 3000);
DISPLAY 0.638298 (-6696 3000);
PAINT MONO (-6696 3000);
DISPLAY INVISIBLE (-6696 3000);
FORCEPROP 2 LAST $XRERR ?
J 0
(-6696 3000);
DISPLAY 0.638298 (-6696 3000);
PAINT MONO (-6696 3000);
DISPLAY INVISIBLE (-6696 3000);
FORCEPROP 2 LAST CDS_LIB mstr_standard
J 0
(-6300 3000);
PAINT ORANGE (-6300 3000);
DISPLAY INVISIBLE (-6300 3000);
FORCEPROP 1 LAST OFFPAGE TRUE
J 0
(-5975 2875);
DISPLAY 1.170213 (-5975 2875);
PAINT GREEN (-5975 2875);
DISPLAY INVISIBLE (-5975 2875);
FORCEPROP 1 LAST COMMENT_BODY TRUE
J 0
(-6175 2900);
DISPLAY 1.170213 (-6175 2900);
PAINT PEACH (-6175 2900);
DISPLAY INVISIBLE (-6175 2900);
FORCEPROP 2 LAST PATH I103
J 0
(-6550 3050);
DISPLAY 1.021277 (-6550 3050);
PAINT ORANGE (-6550 3050);
DISPLAY INVISIBLE (-6550 3050);
FORCEPROP 2 LAST $XRERR ?
J 0
(-6696 3000);
DISPLAY 0.638298 (-6696 3000);
PAINT MONO (-6696 3000);
DISPLAY INVISIBLE (-6696 3000);
FORCEPROP 2 LAST $XRERR ?
J 0
(-6696 3000);
DISPLAY 0.638298 (-6696 3000);
PAINT MONO (-6696 3000);
DISPLAY INVISIBLE (-6696 3000);
FORCEPROP 2 LAST $XRERR ?
J 0
(-6696 3000);
DISPLAY 0.638298 (-6696 3000);
PAINT MONO (-6696 3000);
DISPLAY INVISIBLE (-6696 3000);
FORCEPROP 2 LAST $XRERR ?
J 0
(-6696 3000);
DISPLAY 0.638298 (-6696 3000);
PAINT MONO (-6696 3000);
DISPLAY INVISIBLE (-6696 3000);
FORCEPROP 2 LAST $XRERR ?
J 0
(-6696 3000);
DISPLAY 0.638298 (-6696 3000);
PAINT MONO (-6696 3000);
DISPLAY INVISIBLE (-6696 3000);
FORCEPROP 2 LAST $XRERR ?
J 0
(-6696 3000);
DISPLAY 0.638298 (-6696 3000);
PAINT MONO (-6696 3000);
DISPLAY INVISIBLE (-6696 3000);
FORCEPROP 2 LAST $XRERR ?
J 0
(-6696 3000);
DISPLAY 0.638298 (-6696 3000);
PAINT MONO (-6696 3000);
DISPLAY INVISIBLE (-6696 3000);
FORCEPROP 2 LAST $XRERR UNIQUE?
J 0
(-6696 3000);
DISPLAY 0.638298 (-6696 3000);
PAINT MONO (-6696 3000);
DISPLAY INVISIBLE (-6696 3000);
FORCEADD OFFPAGE..2
(-2175 2950);
FORCEPROP 2 LAST $XR0 ?
J 0
(-1986 2950);
DISPLAY 0.638298 (-1986 2950);
PAINT MONO (-1986 2950);
FORCEPROP 2 LAST $XRERR ?
J 0
(-1986 2950);
DISPLAY 0.638298 (-1986 2950);
PAINT MONO (-1986 2950);
DISPLAY INVISIBLE (-1986 2950);
FORCEPROP 2 LAST $XRERR ?
J 0
(-1986 2950);
DISPLAY 0.638298 (-1986 2950);
PAINT MONO (-1986 2950);
DISPLAY INVISIBLE (-1986 2950);
FORCEPROP 2 LAST $XRERR ?
J 0
(-1986 2950);
DISPLAY 0.638298 (-1986 2950);
PAINT MONO (-1986 2950);
DISPLAY INVISIBLE (-1986 2950);
FORCEPROP 2 LAST $XRERR ?
J 0
(-1986 2950);
DISPLAY 0.638298 (-1986 2950);
PAINT MONO (-1986 2950);
DISPLAY INVISIBLE (-1986 2950);
FORCEPROP 2 LAST $XRERR ?
J 0
(-1986 2950);
DISPLAY 0.638298 (-1986 2950);
PAINT MONO (-1986 2950);
DISPLAY INVISIBLE (-1986 2950);
FORCEPROP 2 LAST $XRERR ?
J 0
(-1986 2950);
DISPLAY 0.638298 (-1986 2950);
PAINT MONO (-1986 2950);
DISPLAY INVISIBLE (-1986 2950);
FORCEPROP 2 LAST $XRERR ?
J 0
(-1986 2950);
DISPLAY 0.638298 (-1986 2950);
PAINT MONO (-1986 2950);
DISPLAY INVISIBLE (-1986 2950);
FORCEPROP 2 LAST CDS_LIB mstr_standard
J 0
(-2175 2950);
PAINT ORANGE (-2175 2950);
DISPLAY INVISIBLE (-2175 2950);
FORCEPROP 1 LAST OFFPAGE TRUE
J 0
(-1850 2825);
DISPLAY 1.170213 (-1850 2825);
PAINT GREEN (-1850 2825);
DISPLAY INVISIBLE (-1850 2825);
FORCEPROP 1 LAST COMMENT_BODY TRUE
J 0
(-2220 2855);
DISPLAY 1.170213 (-2220 2855);
PAINT PEACH (-2220 2855);
DISPLAY INVISIBLE (-2220 2855);
FORCEPROP 2 LAST PATH I104
J 0
(-1975 3000);
DISPLAY 1.021277 (-1975 3000);
PAINT ORANGE (-1975 3000);
DISPLAY INVISIBLE (-1975 3000);
FORCEPROP 2 LAST $XRERR ?
J 0
(-1986 2950);
DISPLAY 0.638298 (-1986 2950);
PAINT MONO (-1986 2950);
DISPLAY INVISIBLE (-1986 2950);
FORCEPROP 2 LAST $XRERR ?
J 0
(-1986 2950);
DISPLAY 0.638298 (-1986 2950);
PAINT MONO (-1986 2950);
DISPLAY INVISIBLE (-1986 2950);
FORCEPROP 2 LAST $XRERR ?
J 0
(-1986 2950);
DISPLAY 0.638298 (-1986 2950);
PAINT MONO (-1986 2950);
DISPLAY INVISIBLE (-1986 2950);
FORCEPROP 2 LAST $XRERR ?
J 0
(-1986 2950);
DISPLAY 0.638298 (-1986 2950);
PAINT MONO (-1986 2950);
DISPLAY INVISIBLE (-1986 2950);
FORCEPROP 2 LAST $XRERR ?
J 0
(-1986 2950);
DISPLAY 0.638298 (-1986 2950);
PAINT MONO (-1986 2950);
DISPLAY INVISIBLE (-1986 2950);
FORCEPROP 2 LAST $XRERR ?
J 0
(-1986 2950);
DISPLAY 0.638298 (-1986 2950);
PAINT MONO (-1986 2950);
DISPLAY INVISIBLE (-1986 2950);
FORCEPROP 2 LAST $XRERR ?
J 0
(-1986 2950);
DISPLAY 0.638298 (-1986 2950);
PAINT MONO (-1986 2950);
DISPLAY INVISIBLE (-1986 2950);
FORCEPROP 2 LAST $XRERR UNIQUE?
J 0
(-1986 2950);
DISPLAY 0.638298 (-1986 2950);
PAINT MONO (-1986 2950);
DISPLAY INVISIBLE (-1986 2950);
FORCEADD OFFPAGE..2
(-2175 3000);
FORCEPROP 2 LAST $XR0 ?
J 0
(-1986 3000);
DISPLAY 0.638298 (-1986 3000);
PAINT MONO (-1986 3000);
FORCEPROP 2 LAST $XRERR ?
J 0
(-1986 3000);
DISPLAY 0.638298 (-1986 3000);
PAINT MONO (-1986 3000);
DISPLAY INVISIBLE (-1986 3000);
FORCEPROP 2 LAST $XRERR ?
J 0
(-1986 3000);
DISPLAY 0.638298 (-1986 3000);
PAINT MONO (-1986 3000);
DISPLAY INVISIBLE (-1986 3000);
FORCEPROP 2 LAST $XRERR ?
J 0
(-1986 3000);
DISPLAY 0.638298 (-1986 3000);
PAINT MONO (-1986 3000);
DISPLAY INVISIBLE (-1986 3000);
FORCEPROP 2 LAST $XRERR ?
J 0
(-1986 3000);
DISPLAY 0.638298 (-1986 3000);
PAINT MONO (-1986 3000);
DISPLAY INVISIBLE (-1986 3000);
FORCEPROP 2 LAST $XRERR ?
J 0
(-1986 3000);
DISPLAY 0.638298 (-1986 3000);
PAINT MONO (-1986 3000);
DISPLAY INVISIBLE (-1986 3000);
FORCEPROP 2 LAST $XRERR ?
J 0
(-1986 3000);
DISPLAY 0.638298 (-1986 3000);
PAINT MONO (-1986 3000);
DISPLAY INVISIBLE (-1986 3000);
FORCEPROP 2 LAST $XRERR ?
J 0
(-1986 3000);
DISPLAY 0.638298 (-1986 3000);
PAINT MONO (-1986 3000);
DISPLAY INVISIBLE (-1986 3000);
FORCEPROP 2 LAST CDS_LIB mstr_standard
J 0
(-2175 3000);
PAINT ORANGE (-2175 3000);
DISPLAY INVISIBLE (-2175 3000);
FORCEPROP 1 LAST OFFPAGE TRUE
J 0
(-1850 2875);
DISPLAY 1.170213 (-1850 2875);
PAINT GREEN (-1850 2875);
DISPLAY INVISIBLE (-1850 2875);
FORCEPROP 1 LAST COMMENT_BODY TRUE
J 0
(-2220 2905);
DISPLAY 1.170213 (-2220 2905);
PAINT PEACH (-2220 2905);
DISPLAY INVISIBLE (-2220 2905);
FORCEPROP 2 LAST PATH I105
J 0
(-1975 3050);
DISPLAY 1.021277 (-1975 3050);
PAINT ORANGE (-1975 3050);
DISPLAY INVISIBLE (-1975 3050);
FORCEPROP 2 LAST $XRERR ?
J 0
(-1986 3000);
DISPLAY 0.638298 (-1986 3000);
PAINT MONO (-1986 3000);
DISPLAY INVISIBLE (-1986 3000);
FORCEPROP 2 LAST $XRERR ?
J 0
(-1986 3000);
DISPLAY 0.638298 (-1986 3000);
PAINT MONO (-1986 3000);
DISPLAY INVISIBLE (-1986 3000);
FORCEPROP 2 LAST $XRERR ?
J 0
(-1986 3000);
DISPLAY 0.638298 (-1986 3000);
PAINT MONO (-1986 3000);
DISPLAY INVISIBLE (-1986 3000);
FORCEPROP 2 LAST $XRERR ?
J 0
(-1986 3000);
DISPLAY 0.638298 (-1986 3000);
PAINT MONO (-1986 3000);
DISPLAY INVISIBLE (-1986 3000);
FORCEPROP 2 LAST $XRERR ?
J 0
(-1986 3000);
DISPLAY 0.638298 (-1986 3000);
PAINT MONO (-1986 3000);
DISPLAY INVISIBLE (-1986 3000);
FORCEPROP 2 LAST $XRERR ?
J 0
(-1986 3000);
DISPLAY 0.638298 (-1986 3000);
PAINT MONO (-1986 3000);
DISPLAY INVISIBLE (-1986 3000);
FORCEPROP 2 LAST $XRERR ?
J 0
(-1986 3000);
DISPLAY 0.638298 (-1986 3000);
PAINT MONO (-1986 3000);
DISPLAY INVISIBLE (-1986 3000);
FORCEPROP 2 LAST $XRERR UNIQUE?
J 0
(-1986 3000);
DISPLAY 0.638298 (-1986 3000);
PAINT MONO (-1986 3000);
DISPLAY INVISIBLE (-1986 3000);
FORCEADD OFFPAGE..3
(-2175 1550);
FORCEPROP 2 LAST $XR0 176 
J 0
(-1961 1550);
DISPLAY 0.638298 (-1961 1550);
PAINT MONO (-1961 1550);
FORCEPROP 2 LAST CDS_LIB mstr_standard
J 0
(-2175 1550);
PAINT ORANGE (-2175 1550);
DISPLAY INVISIBLE (-2175 1550);
FORCEPROP 1 LAST OFFPAGE TRUE
J 0
(-1850 1425);
DISPLAY 1.170213 (-1850 1425);
PAINT GREEN (-1850 1425);
DISPLAY INVISIBLE (-1850 1425);
FORCEPROP 1 LAST COMMENT_BODY TRUE
J 0
(-2225 1450);
DISPLAY 1.170213 (-2225 1450);
PAINT PEACH (-2225 1450);
DISPLAY INVISIBLE (-2225 1450);
FORCEPROP 2 LAST PATH I106
J 0
(-1950 1600);
DISPLAY 1.021277 (-1950 1600);
PAINT ORANGE (-1950 1600);
DISPLAY INVISIBLE (-1950 1600);
FORCEADD OFFPAGE..3
(-2175 1500);
FORCEPROP 2 LAST $XR0 176 
J 0
(-1961 1500);
DISPLAY 0.638298 (-1961 1500);
PAINT MONO (-1961 1500);
FORCEPROP 2 LAST CDS_LIB mstr_standard
J 0
(-2175 1500);
PAINT ORANGE (-2175 1500);
DISPLAY INVISIBLE (-2175 1500);
FORCEPROP 1 LAST OFFPAGE TRUE
J 0
(-1850 1375);
DISPLAY 1.170213 (-1850 1375);
PAINT GREEN (-1850 1375);
DISPLAY INVISIBLE (-1850 1375);
FORCEPROP 1 LAST COMMENT_BODY TRUE
J 0
(-2225 1400);
DISPLAY 1.170213 (-2225 1400);
PAINT PEACH (-2225 1400);
DISPLAY INVISIBLE (-2225 1400);
FORCEPROP 2 LAST PATH I107
J 0
(-1950 1550);
DISPLAY 1.021277 (-1950 1550);
PAINT ORANGE (-1950 1550);
DISPLAY INVISIBLE (-1950 1550);
FORCEADD OFFPAGE..3
(-2175 1850);
FORCEPROP 2 LAST $XR0 146 
J 0
(-1961 1850);
DISPLAY 0.638298 (-1961 1850);
PAINT MONO (-1961 1850);
FORCEPROP 2 LAST CDS_LIB mstr_standard
J 0
(-2175 1850);
PAINT ORANGE (-2175 1850);
DISPLAY INVISIBLE (-2175 1850);
FORCEPROP 1 LAST OFFPAGE TRUE
J 0
(-1850 1725);
DISPLAY 1.170213 (-1850 1725);
PAINT GREEN (-1850 1725);
DISPLAY INVISIBLE (-1850 1725);
FORCEPROP 1 LAST COMMENT_BODY TRUE
J 0
(-2225 1750);
DISPLAY 1.170213 (-2225 1750);
PAINT PEACH (-2225 1750);
DISPLAY INVISIBLE (-2225 1750);
FORCEPROP 2 LAST PATH I110
J 0
(-1950 1900);
DISPLAY 1.021277 (-1950 1900);
PAINT ORANGE (-1950 1900);
DISPLAY INVISIBLE (-1950 1900);
FORCEADD OFFPAGE..3
(-2175 1800);
FORCEPROP 2 LAST $XR0 146 
J 0
(-1961 1800);
DISPLAY 0.638298 (-1961 1800);
PAINT MONO (-1961 1800);
FORCEPROP 2 LAST CDS_LIB mstr_standard
J 0
(-2175 1800);
PAINT ORANGE (-2175 1800);
DISPLAY INVISIBLE (-2175 1800);
FORCEPROP 2 LAST PATH I111
J 0
(-1950 1850);
DISPLAY 1.021277 (-1950 1850);
PAINT ORANGE (-1950 1850);
DISPLAY INVISIBLE (-1950 1850);
FORCEPROP 1 LAST COMMENT_BODY TRUE
J 0
(-2225 1700);
DISPLAY 1.170213 (-2225 1700);
PAINT PEACH (-2225 1700);
DISPLAY INVISIBLE (-2225 1700);
FORCEPROP 1 LAST OFFPAGE TRUE
J 0
(-1850 1675);
DISPLAY 1.170213 (-1850 1675);
PAINT GREEN (-1850 1675);
DISPLAY INVISIBLE (-1850 1675);
FORCEADD OFFPAGE..3
(-2175 1900);
FORCEPROP 2 LAST $XR0 146 
J 0
(-1961 1900);
DISPLAY 0.638298 (-1961 1900);
PAINT MONO (-1961 1900);
FORCEPROP 2 LAST CDS_LIB mstr_standard
J 0
(-2175 1900);
PAINT ORANGE (-2175 1900);
DISPLAY INVISIBLE (-2175 1900);
FORCEPROP 1 LAST OFFPAGE TRUE
J 0
(-1850 1775);
DISPLAY 1.170213 (-1850 1775);
PAINT GREEN (-1850 1775);
DISPLAY INVISIBLE (-1850 1775);
FORCEPROP 1 LAST COMMENT_BODY TRUE
J 0
(-2225 1800);
DISPLAY 1.170213 (-2225 1800);
PAINT PEACH (-2225 1800);
DISPLAY INVISIBLE (-2225 1800);
FORCEPROP 2 LAST PATH I112
J 0
(-1950 1950);
DISPLAY 1.021277 (-1950 1950);
PAINT ORANGE (-1950 1950);
DISPLAY INVISIBLE (-1950 1950);
FORCEADD OFFPAGE..3
(-2175 1950);
FORCEPROP 2 LAST $XR0 146 
J 0
(-1961 1950);
DISPLAY 0.638298 (-1961 1950);
PAINT MONO (-1961 1950);
FORCEPROP 2 LAST CDS_LIB mstr_standard
J 0
(-2175 1950);
PAINT ORANGE (-2175 1950);
DISPLAY INVISIBLE (-2175 1950);
FORCEPROP 1 LAST OFFPAGE TRUE
J 0
(-1850 1825);
DISPLAY 1.170213 (-1850 1825);
PAINT GREEN (-1850 1825);
DISPLAY INVISIBLE (-1850 1825);
FORCEPROP 1 LAST COMMENT_BODY TRUE
J 0
(-2225 1850);
DISPLAY 1.170213 (-2225 1850);
PAINT PEACH (-2225 1850);
DISPLAY INVISIBLE (-2225 1850);
FORCEPROP 2 LAST PATH I113
J 0
(-1950 2000);
DISPLAY 1.021277 (-1950 2000);
PAINT ORANGE (-1950 2000);
DISPLAY INVISIBLE (-1950 2000);
FORCEADD RES..2
(-5425 1775);
FORCEPROP 1 LAST LOCATION R8B32
J 0
(-5380 1900);
DISPLAY 0.617021 (-5380 1900);
PAINT AQUA (-5380 1900);
FORCEPROP 1 LAST PART_NUMBER G21796-016
J 0
(-5385 1650);
DISPLAY 0.617021 (-5385 1650);
PAINT BLUE (-5385 1650);
FORCEPROP 1 LAST VALUE 10.0K
J 0
(-5380 1850);
DISPLAY 0.617021 (-5380 1850);
PAINT SKYBLUE (-5380 1850);
FORCEPROP 1 LAST TOLERANCE 1%
J 0
(-5380 1800);
DISPLAY 0.617021 (-5380 1800);
PAINT SKYBLUE (-5380 1800);
FORCEPROP 1 LAST PACK_TYPE 0402
J 0
(-5385 1600);
DISPLAY 0.617021 (-5385 1600);
PAINT SKYBLUE (-5385 1600);
FORCEPROP 1 LAST MATERIAL CHIP
J 0
(-5385 1700);
DISPLAY 0.617021 (-5385 1700);
PAINT SKYBLUE (-5385 1700);
FORCEPROP 1 LAST WATTAGE 1/16W
J 0
(-5385 1750);
DISPLAY 0.617021 (-5385 1750);
PAINT SKYBLUE (-5385 1750);
FORCEPROP 1 LASTPIN (-5425 1875) $PN 1
J 0
(-5420 1837);
DISPLAY 0.617021 (-5420 1837);
PAINT ORANGE (-5420 1837);
FORCEPROP 1 LASTPIN (-5425 1675) $PN 2
J 0
(-5420 1685);
DISPLAY 0.617021 (-5420 1685);
PAINT ORANGE (-5420 1685);
FORCEPROP 2 LAST SEC 1
J 0
(-5375 2000);
DISPLAY 0.680851 (-5375 2000);
PAINT MONO (-5375 2000);
DISPLAY INVISIBLE (-5375 2000);
FORCEPROP 2 LAST CDS_LIB mstr_discrete
J 0
(-5425 1775);
PAINT ORANGE (-5425 1775);
DISPLAY INVISIBLE (-5425 1775);
FORCEPROP 2 LAST SEC_TYPE 0402
J 0
(-5375 2000);
DISPLAY 1.021277 (-5375 2000);
PAINT ORANGE (-5375 2000);
DISPLAY INVISIBLE (-5375 2000);
FORCEPROP 1 LAST PATH I114
J 0
(-5375 1950);
DISPLAY 0.978723 (-5375 1950);
PAINT WHITE (-5375 1950);
DISPLAY INVISIBLE (-5375 1950);
FORCEADD GND..1
(-5425 1550);
FORCEPROP 3 LASTPIN (-5425 1600) SIG_NAME GND\g
J 0
(-5415 1610);
DISPLAY 0.659574 (-5415 1610);
PAINT MONO (-5415 1610);
DISPLAY INVISIBLE (-5415 1610);
FORCEPROP 1 LAST VOLTAGE 0.0V
J 0
(-5470 1507);
DISPLAY 0.340426 (-5470 1507);
PAINT SKYBLUE (-5470 1507);
DISPLAY INVISIBLE (-5470 1507);
FORCEPROP 2 LAST CDS_LIB mstr_symbols
J 0
(-5425 1550);
PAINT ORANGE (-5425 1550);
DISPLAY INVISIBLE (-5425 1550);
FORCEPROP 1 LAST SIZE 1B
J 0
(-5350 1500);
DISPLAY 0.872340 (-5350 1500);
PAINT AQUA (-5350 1500);
DISPLAY INVISIBLE (-5350 1500);
FORCEPROP 1 LAST BODY_TYPE PLUMBING
J 0
(-5470 1507);
DISPLAY 0.340426 (-5470 1507);
PAINT GREEN (-5470 1507);
DISPLAY INVISIBLE (-5470 1507);
FORCEPROP 1 LAST PATH I115
J 0
(-5350 1550);
DISPLAY 0.872340 (-5350 1550);
PAINT AQUA (-5350 1550);
DISPLAY INVISIBLE (-5350 1550);
FORCEPROP 1 LAST HDL_POWER GND
J 0
(-5425 1700);
DISPLAY 0.702128 (-5425 1700);
PAINT GREEN (-5425 1700);
DISPLAY INVISIBLE (-5425 1700);
FORCEADD OFFPAGE..3
(-2175 1650);
FORCEPROP 2 LAST $XR0 245 
J 0
(-1990 1650);
DISPLAY 0.638298 (-1990 1650);
PAINT MONO (-1990 1650);
FORCEPROP 2 LAST CDS_LIB mstr_standard
J 0
(-2175 1650);
PAINT MONO (-2175 1650);
DISPLAY INVISIBLE (-2175 1650);
FORCEPROP 2 LAST PATH I116
J 0
(-1975 1725);
DISPLAY 1.021277 (-1975 1725);
PAINT ORANGE (-1975 1725);
DISPLAY INVISIBLE (-1975 1725);
FORCEPROP 1 LAST OFFPAGE TRUE
J 0
(-1850 1525);
DISPLAY 1.170213 (-1850 1525);
PAINT GREEN (-1850 1525);
DISPLAY INVISIBLE (-1850 1525);
FORCEPROP 1 LAST COMMENT_BODY TRUE
J 0
(-2225 1550);
DISPLAY 1.170213 (-2225 1550);
PAINT PEACH (-2225 1550);
DISPLAY INVISIBLE (-2225 1550);
FORCEADD OFFPAGE..3
(-2175 1600);
FORCEPROP 2 LAST $XR0 245 
J 0
(-1965 1600);
DISPLAY 0.638298 (-1965 1600);
PAINT MONO (-1965 1600);
FORCEPROP 2 LAST CDS_LIB mstr_standard
J 0
(-2175 1600);
PAINT MONO (-2175 1600);
DISPLAY INVISIBLE (-2175 1600);
FORCEPROP 2 LAST PATH I117
J 0
(-1975 1675);
DISPLAY 1.021277 (-1975 1675);
PAINT ORANGE (-1975 1675);
DISPLAY INVISIBLE (-1975 1675);
FORCEPROP 1 LAST OFFPAGE TRUE
J 0
(-1850 1475);
DISPLAY 1.170213 (-1850 1475);
PAINT GREEN (-1850 1475);
DISPLAY INVISIBLE (-1850 1475);
FORCEPROP 1 LAST COMMENT_BODY TRUE
J 0
(-2225 1500);
DISPLAY 1.170213 (-2225 1500);
PAINT PEACH (-2225 1500);
DISPLAY INVISIBLE (-2225 1500);
FORCEADD LBG_CORE_QAT_EXT_D..2
(-4000 2500);
FORCEPROP 1 LAST LOCATION U7C1
J 0
(-4700 3750);
DISPLAY 0.617021 (-4700 3750);
PAINT AQUA (-4700 3750);
FORCEPROP 1 LAST PART_NUMBER H91415-002
J 0
(-4700 1300);
DISPLAY 0.617021 (-4700 1300);
PAINT BLUE (-4700 1300);
FORCEPROP 1 LAST MATERIAL IC
J 0
(-4700 3700);
DISPLAY 0.617021 (-4700 3700);
PAINT SKYBLUE (-4700 3700);
FORCEPROP 2 LASTPIN (-4750 2050) $PN BN68
J 2
(-4760 2060);
DISPLAY 0.617021 (-4760 2060);
PAINT ORANGE (-4760 2060);
FORCEPROP 2 LASTPIN (-3250 1500) $PN BY60
J 0
(-3240 1510);
DISPLAY 0.617021 (-3240 1510);
PAINT ORANGE (-3240 1510);
FORCEPROP 2 LASTPIN (-3250 2400) $PN BW65
J 0
(-3240 2410);
DISPLAY 0.617021 (-3240 2410);
PAINT ORANGE (-3240 2410);
FORCEPROP 2 LASTPIN (-3250 2500) $PN CA54
J 0
(-3240 2510);
DISPLAY 0.617021 (-3240 2510);
PAINT ORANGE (-3240 2510);
FORCEPROP 2 LASTPIN (-3250 2600) $PN BW67
J 0
(-3240 2610);
DISPLAY 0.617021 (-3240 2610);
PAINT ORANGE (-3240 2610);
FORCEPROP 2 LASTPIN (-3250 2700) $PN BY53
J 0
(-3240 2710);
DISPLAY 0.617021 (-3240 2710);
PAINT ORANGE (-3240 2710);
FORCEPROP 2 LASTPIN (-3250 2800) $PN BW68
J 0
(-3240 2810);
DISPLAY 0.617021 (-3240 2810);
PAINT ORANGE (-3240 2810);
FORCEPROP 2 LASTPIN (-3250 1600) $PN CA61
J 0
(-3240 1610);
DISPLAY 0.617021 (-3240 1610);
PAINT ORANGE (-3240 1610);
FORCEPROP 2 LASTPIN (-3250 1700) $PN CA59
J 0
(-3240 1710);
DISPLAY 0.617021 (-3240 1710);
PAINT ORANGE (-3240 1710);
FORCEPROP 2 LASTPIN (-3250 1800) $PN BY62
J 0
(-3240 1810);
DISPLAY 0.617021 (-3240 1810);
PAINT ORANGE (-3240 1810);
FORCEPROP 2 LASTPIN (-3250 1900) $PN BY58
J 0
(-3240 1910);
DISPLAY 0.617021 (-3240 1910);
PAINT ORANGE (-3240 1910);
FORCEPROP 2 LASTPIN (-3250 2000) $PN CA63
J 0
(-3240 2010);
DISPLAY 0.617021 (-3240 2010);
PAINT ORANGE (-3240 2010);
FORCEPROP 2 LASTPIN (-3250 2100) $PN CA57
J 0
(-3240 2110);
DISPLAY 0.617021 (-3240 2110);
PAINT ORANGE (-3240 2110);
FORCEPROP 2 LASTPIN (-3250 2200) $PN BY64
J 0
(-3240 2210);
DISPLAY 0.617021 (-3240 2210);
PAINT ORANGE (-3240 2210);
FORCEPROP 2 LASTPIN (-3250 2300) $PN BY55
J 0
(-3240 2310);
DISPLAY 0.617021 (-3240 2310);
PAINT ORANGE (-3240 2310);
FORCEPROP 2 LASTPIN (-3250 1550) $PN BV60
J 0
(-3240 1560);
DISPLAY 0.617021 (-3240 1560);
PAINT ORANGE (-3240 1560);
FORCEPROP 2 LASTPIN (-3250 2450) $PN BU65
J 0
(-3240 2460);
DISPLAY 0.617021 (-3240 2460);
PAINT ORANGE (-3240 2460);
FORCEPROP 2 LASTPIN (-3250 2550) $PN BW54
J 0
(-3240 2560);
DISPLAY 0.617021 (-3240 2560);
PAINT ORANGE (-3240 2560);
FORCEPROP 2 LASTPIN (-3250 2650) $PN BV66
J 0
(-3240 2660);
DISPLAY 0.617021 (-3240 2660);
PAINT ORANGE (-3240 2660);
FORCEPROP 2 LASTPIN (-3250 2750) $PN BV53
J 0
(-3240 2760);
DISPLAY 0.617021 (-3240 2760);
PAINT ORANGE (-3240 2760);
FORCEPROP 2 LASTPIN (-3250 2850) $PN BU67
J 0
(-3240 2860);
DISPLAY 0.617021 (-3240 2860);
PAINT ORANGE (-3240 2860);
FORCEPROP 2 LASTPIN (-3250 1650) $PN BW61
J 0
(-3240 1660);
DISPLAY 0.617021 (-3240 1660);
PAINT ORANGE (-3240 1660);
FORCEPROP 2 LASTPIN (-3250 1750) $PN BW59
J 0
(-3240 1760);
DISPLAY 0.617021 (-3240 1760);
PAINT ORANGE (-3240 1760);
FORCEPROP 2 LASTPIN (-3250 1850) $PN BV62
J 0
(-3240 1860);
DISPLAY 0.617021 (-3240 1860);
PAINT ORANGE (-3240 1860);
FORCEPROP 2 LASTPIN (-3250 1950) $PN BV58
J 0
(-3240 1960);
DISPLAY 0.617021 (-3240 1960);
PAINT ORANGE (-3240 1960);
FORCEPROP 2 LASTPIN (-3250 2050) $PN BW63
J 0
(-3240 2060);
DISPLAY 0.617021 (-3240 2060);
PAINT ORANGE (-3240 2060);
FORCEPROP 2 LASTPIN (-3250 2150) $PN BW57
J 0
(-3240 2160);
DISPLAY 0.617021 (-3240 2160);
PAINT ORANGE (-3240 2160);
FORCEPROP 2 LASTPIN (-3250 2250) $PN BV64
J 0
(-3240 2260);
DISPLAY 0.617021 (-3240 2260);
PAINT ORANGE (-3240 2260);
FORCEPROP 2 LASTPIN (-3250 2350) $PN BV55
J 0
(-3240 2360);
DISPLAY 0.617021 (-3240 2360);
PAINT ORANGE (-3240 2360);
FORCEPROP 2 LASTPIN (-4750 1950) $PN BR67
J 2
(-4760 1960);
DISPLAY 0.617021 (-4760 1960);
PAINT ORANGE (-4760 1960);
FORCEPROP 2 LASTPIN (-4750 2950) $PN BK71
J 2
(-4760 2960);
DISPLAY 0.617021 (-4760 2960);
PAINT ORANGE (-4760 2960);
FORCEPROP 2 LASTPIN (-4750 3000) $PN BK69
J 2
(-4760 3010);
DISPLAY 0.617021 (-4760 3010);
PAINT ORANGE (-4760 3010);
FORCEPROP 2 LASTPIN (-3250 2950) $PN BL52
J 0
(-3240 2960);
DISPLAY 0.617021 (-3240 2960);
PAINT ORANGE (-3240 2960);
FORCEPROP 2 LASTPIN (-3250 3000) $PN BK54
J 0
(-3240 3010);
DISPLAY 0.617021 (-3240 3010);
PAINT ORANGE (-3240 3010);
FORCEPROP 2 LASTPIN (-4750 3050) $PN BJ72
J 2
(-4760 3060);
DISPLAY 0.617021 (-4760 3060);
PAINT ORANGE (-4760 3060);
FORCEPROP 2 LASTPIN (-4750 3100) $PN BJ70
J 2
(-4760 3110);
DISPLAY 0.617021 (-4760 3110);
PAINT ORANGE (-4760 3110);
FORCEPROP 2 LASTPIN (-3250 3050) $PN BL56
J 0
(-3240 3060);
DISPLAY 0.617021 (-3240 3060);
PAINT ORANGE (-3240 3060);
FORCEPROP 2 LASTPIN (-3250 3100) $PN BJ56
J 0
(-3240 3110);
DISPLAY 0.617021 (-3240 3110);
PAINT ORANGE (-3240 3110);
FORCEPROP 2 LASTPIN (-4750 3150) $PN BH71
J 2
(-4760 3160);
DISPLAY 0.617021 (-4760 3160);
PAINT ORANGE (-4760 3160);
FORCEPROP 2 LASTPIN (-4750 3200) $PN BH69
J 2
(-4760 3210);
DISPLAY 0.617021 (-4760 3210);
PAINT ORANGE (-4760 3210);
FORCEPROP 2 LASTPIN (-3250 3150) $PN BM54
J 0
(-3240 3160);
DISPLAY 0.617021 (-3240 3160);
PAINT ORANGE (-3240 3160);
FORCEPROP 2 LASTPIN (-3250 3200) $PN BN56
J 0
(-3240 3210);
DISPLAY 0.617021 (-3240 3210);
PAINT ORANGE (-3240 3210);
FORCEPROP 2 LASTPIN (-4750 3250) $PN BF72
J 2
(-4760 3260);
DISPLAY 0.617021 (-4760 3260);
PAINT ORANGE (-4760 3260);
FORCEPROP 2 LASTPIN (-4750 3300) $PN BF70
J 2
(-4760 3310);
DISPLAY 0.617021 (-4760 3310);
PAINT ORANGE (-4760 3310);
FORCEPROP 2 LASTPIN (-3250 3250) $PN BH58
J 0
(-3240 3260);
DISPLAY 0.617021 (-3240 3260);
PAINT ORANGE (-3240 3260);
FORCEPROP 2 LASTPIN (-3250 3300) $PN BG56
J 0
(-3240 3310);
DISPLAY 0.617021 (-3240 3310);
PAINT ORANGE (-3240 3310);
FORCEPROP 2 LASTPIN (-4750 3350) $PN BE71
J 2
(-4760 3360);
DISPLAY 0.617021 (-4760 3360);
PAINT ORANGE (-4760 3360);
FORCEPROP 2 LASTPIN (-4750 3400) $PN BE69
J 2
(-4760 3410);
DISPLAY 0.617021 (-4760 3410);
PAINT ORANGE (-4760 3410);
FORCEPROP 2 LASTPIN (-3250 3350) $PN BK58
J 0
(-3240 3360);
DISPLAY 0.617021 (-3240 3360);
PAINT ORANGE (-3240 3360);
FORCEPROP 2 LASTPIN (-3250 3400) $PN BJ59
J 0
(-3240 3410);
DISPLAY 0.617021 (-3240 3410);
PAINT ORANGE (-3240 3410);
FORCEPROP 2 LASTPIN (-4750 3450) $PN BD72
J 2
(-4760 3460);
DISPLAY 0.617021 (-4760 3460);
PAINT ORANGE (-4760 3460);
FORCEPROP 2 LASTPIN (-4750 3500) $PN BD70
J 2
(-4760 3510);
DISPLAY 0.617021 (-4760 3510);
PAINT ORANGE (-4760 3510);
FORCEPROP 2 LASTPIN (-3250 3450) $PN BL59
J 0
(-3240 3460);
DISPLAY 0.617021 (-3240 3460);
PAINT ORANGE (-3240 3460);
FORCEPROP 2 LASTPIN (-3250 3500) $PN BM61
J 0
(-3240 3510);
DISPLAY 0.617021 (-3240 3510);
PAINT ORANGE (-3240 3510);
FORCEPROP 2 LASTPIN (-4750 2150) $PN BN70
J 2
(-4760 2160);
DISPLAY 0.617021 (-4760 2160);
PAINT ORANGE (-4760 2160);
FORCEPROP 1 LAST PACK_TYPE BGA1
J 0
(-4700 3800);
PAINT SKYBLUE (-4700 3800);
DISPLAY INVISIBLE (-4700 3800);
FORCEPROP 2 LAST SEC_TYPE BGA1
J 0
(-4700 3800);
DISPLAY 1.021277 (-4700 3800);
PAINT ORANGE (-4700 3800);
DISPLAY INVISIBLE (-4700 3800);
FORCEPROP 2 LAST SEC 2
J 0
(-4700 3800);
DISPLAY 0.680851 (-4700 3800);
PAINT MONO (-4700 3800);
DISPLAY INVISIBLE (-4700 3800);
FORCEPROP 2 LAST CDS_LIB mstr_u_proc
J 0
(-4000 2500);
PAINT ORANGE (-4000 2500);
DISPLAY INVISIBLE (-4000 2500);
FORCEPROP 0 LAST BOM_COST SB
J 0
(-5350 4350);
DISPLAY 1.361702 (-5350 4350);
PAINT ORANGE (-5350 4350);
DISPLAY INVISIBLE (-5350 4350);
FORCEPROP 2 LAST CDS_LOCATION U7C1
J 0
(-4700 3750);
DISPLAY 0.617021 (-4700 3750);
PAINT AQUA (-4700 3750);
DISPLAY INVISIBLE (-4700 3750);
FORCEPROP 1 LAST PATH I74
J 0
(-4000 3700);
PAINT GREEN (-4000 3700);
DISPLAY INVISIBLE (-4000 3700);
FORCEPROP 0 LAST ROOM SB
J 0
(-5350 4250);
DISPLAY 1.361702 (-5350 4250);
PAINT ORANGE (-5350 4250);
DISPLAY INVISIBLE (-5350 4250);
FORCEADD RES..2
(-5750 1775);
FORCEPROP 1 LAST LOCATION R8B9
J 0
(-5705 1900);
DISPLAY 0.617021 (-5705 1900);
PAINT AQUA (-5705 1900);
FORCEPROP 1 LAST PART_NUMBER G21796-341
J 0
(-5710 1650);
DISPLAY 0.617021 (-5710 1650);
PAINT BLUE (-5710 1650);
FORCEPROP 1 LAST VALUE 113
J 0
(-5705 1850);
DISPLAY 0.617021 (-5705 1850);
PAINT SKYBLUE (-5705 1850);
FORCEPROP 1 LAST TOLERANCE 1%
J 0
(-5705 1800);
DISPLAY 0.617021 (-5705 1800);
PAINT SKYBLUE (-5705 1800);
FORCEPROP 1 LAST PACK_TYPE 0402
J 0
(-5710 1600);
DISPLAY 0.617021 (-5710 1600);
PAINT SKYBLUE (-5710 1600);
FORCEPROP 1 LAST MATERIAL CHIP
J 0
(-5710 1700);
DISPLAY 0.617021 (-5710 1700);
PAINT SKYBLUE (-5710 1700);
FORCEPROP 1 LAST WATTAGE 1/16W
J 0
(-5710 1750);
DISPLAY 0.617021 (-5710 1750);
PAINT SKYBLUE (-5710 1750);
FORCEPROP 1 LASTPIN (-5750 1875) $PN 1
J 0
(-5745 1837);
DISPLAY 0.617021 (-5745 1837);
PAINT WHITE (-5745 1837);
FORCEPROP 1 LASTPIN (-5750 1675) $PN 2
J 0
(-5745 1685);
DISPLAY 0.617021 (-5745 1685);
PAINT WHITE (-5745 1685);
FORCEPROP 2 LAST CDS_LOCATION R8B9
J 0
(-5705 1900);
DISPLAY 0.617021 (-5705 1900);
PAINT AQUA (-5705 1900);
DISPLAY INVISIBLE (-5705 1900);
FORCEPROP 2 LAST SEC 1
J 0
(-5700 2000);
DISPLAY 0.680851 (-5700 2000);
PAINT MONO (-5700 2000);
DISPLAY INVISIBLE (-5700 2000);
FORCEPROP 2 LAST SEC_TYPE 0402
J 0
(-5700 2000);
DISPLAY 1.021277 (-5700 2000);
PAINT ORANGE (-5700 2000);
DISPLAY INVISIBLE (-5700 2000);
FORCEPROP 2 LAST CDS_LIB mstr_discrete
J 0
(-5750 1775);
PAINT ORANGE (-5750 1775);
DISPLAY INVISIBLE (-5750 1775);
FORCEPROP 1 LAST PATH I90
J 0
(-5700 1950);
DISPLAY 0.978723 (-5700 1950);
PAINT WHITE (-5700 1950);
DISPLAY INVISIBLE (-5700 1950);
FORCEPROP 0 LAST ROOM SB
J 0
(-5700 2000);
DISPLAY 1.021277 (-5700 2000);
PAINT ORANGE (-5700 2000);
DISPLAY INVISIBLE (-5700 2000);
FORCEADD GND..1
(-5750 1550);
FORCEPROP 3 LASTPIN (-5750 1600) SIG_NAME GND\g
J 0
(-5740 1610);
DISPLAY 0.659574 (-5740 1610);
PAINT MONO (-5740 1610);
DISPLAY INVISIBLE (-5740 1610);
FORCEPROP 1 LAST VOLTAGE 0.0V
J 0
(-5795 1507);
DISPLAY 0.340426 (-5795 1507);
PAINT SKYBLUE (-5795 1507);
DISPLAY INVISIBLE (-5795 1507);
FORCEPROP 1 LAST SIZE 1B
J 0
(-5675 1500);
DISPLAY 0.872340 (-5675 1500);
PAINT AQUA (-5675 1500);
DISPLAY INVISIBLE (-5675 1500);
FORCEPROP 2 LAST CDS_LIB mstr_symbols
J 0
(-5750 1550);
PAINT ORANGE (-5750 1550);
DISPLAY INVISIBLE (-5750 1550);
FORCEPROP 1 LAST BODY_TYPE PLUMBING
J 0
(-5795 1507);
DISPLAY 0.340426 (-5795 1507);
PAINT GREEN (-5795 1507);
DISPLAY INVISIBLE (-5795 1507);
FORCEPROP 1 LAST PATH I91
J 0
(-5675 1550);
DISPLAY 0.872340 (-5675 1550);
PAINT AQUA (-5675 1550);
DISPLAY INVISIBLE (-5675 1550);
FORCEPROP 1 LAST HDL_POWER GND
J 0
(-5750 1700);
DISPLAY 0.702128 (-5750 1700);
PAINT GREEN (-5750 1700);
DISPLAY INVISIBLE (-5750 1700);
FORCEADD CAD_NOTE..1
(-6275 2425);
FORCEPROP 0 LAST L2 WITHIN 0.5 INCH OF PCH
J 0
(-6400 2225);
DISPLAY 1.021277 (-6400 2225);
PAINT ORANGE (-6400 2225);
FORCEPROP 0 LAST L1 PLACE USB2_COMP RES ON TOP
J 0
(-6400 2300);
DISPLAY 0.936170 (-6400 2300);
PAINT WHITE (-6400 2300);
FORCEPROP 2 LAST CDS_LIB mstr_symbols
J 0
(-6275 2425);
PAINT ORANGE (-6275 2425);
DISPLAY INVISIBLE (-6275 2425);
FORCEPROP 1 LAST COMMENT_BODY TRUE
J 0
(-6250 2525);
DISPLAY 1.595745 (-6250 2525);
PAINT PEACH (-6250 2525);
DISPLAY INVISIBLE (-6250 2525);
FORCEADD DESIGN_NOTE..1
(-8200 900);
FORCEPROP 0 LAST L6 OVER CURRENT
J 1
(-5400 675);
DISPLAY 1.361702 (-5400 675);
PAINT ORANGE (-5400 675);
FORCEPROP 0 LAST L25 PORT 5
J 1
(-5975 375);
DISPLAY 1.021277 (-5975 375);
PAINT ORANGE (-5975 375);
FORCEPROP 0 LAST L9 PORT 1
J 1
(-6400 575);
DISPLAY 1.021277 (-6400 575);
PAINT ORANGE (-6400 575);
FORCEPROP 0 LAST L24 ---
J 1
(-6400 375);
DISPLAY 1.021277 (-6400 375);
PAINT ORANGE (-6400 375);
FORCEPROP 0 LAST L19 ---
J 1
(-6400 475);
DISPLAY 1.021277 (-6400 475);
PAINT ORANGE (-6400 475);
FORCEPROP 0 LAST L26 ---
J 1
(-5400 375);
DISPLAY 1.021277 (-5400 375);
PAINT ORANGE (-5400 375);
FORCEPROP 0 LAST L21 ---
J 1
(-5400 475);
DISPLAY 1.021277 (-5400 475);
PAINT ORANGE (-5400 475);
FORCEPROP 0 LAST L11 OCB_0
J 1
(-5400 575);
DISPLAY 1.021277 (-5400 575);
PAINT ORANGE (-5400 575);
FORCEPROP 0 LAST L5 USB2.0
J 1
(-5975 675);
DISPLAY 1.361702 (-5975 675);
PAINT ORANGE (-5975 675);
FORCEPROP 0 LAST L20 PORT 4
J 1
(-5975 475);
DISPLAY 1.021277 (-5975 475);
PAINT ORANGE (-5975 475);
FORCEPROP 0 LAST L10 PORT 1
J 1
(-5975 575);
DISPLAY 1.021277 (-5975 575);
PAINT ORANGE (-5975 575);
FORCEPROP 0 LAST L22 BMC
J 0
(-8400 375);
DISPLAY 1.021277 (-8400 375);
PAINT ORANGE (-8400 375);
FORCEPROP 0 LAST L17 BMC
J 0
(-8400 475);
DISPLAY 1.085106 (-8400 475);
PAINT ORANGE (-8400 475);
FORCEPROP 0 LAST L4 USB3.0
J 1
(-6375 675);
DISPLAY 1.361702 (-6375 675);
PAINT ORANGE (-6375 675);
FORCEPROP 0 LAST L2 TOPOLOGY
J 0
(-8400 675);
DISPLAY 1.361702 (-8400 675);
PAINT ORANGE (-8400 675);
FORCEPROP 0 LAST L7 BACK PANEL
J 0
(-8400 575);
DISPLAY 1.085106 (-8400 575);
PAINT ORANGE (-8400 575);
FORCEPROP 0 LAST L1 USB PORT ASSIGNMENT
J 0
(-8400 775);
DISPLAY 1.361702 (-8400 775);
PAINT ORANGE (-8400 775);
FORCEPROP 0 LAST L18 ON-BOARD
J 0
(-7650 375);
DISPLAY 1.021277 (-7650 375);
PAINT ORANGE (-7650 375);
FORCEPROP 0 LAST L13 ON-BOARD
J 0
(-7650 475);
DISPLAY 1.021277 (-7650 475);
PAINT ORANGE (-7650 475);
FORCEPROP 0 LAST L8 FRONT (RIGHT ANGLE)
J 0
(-7650 575);
DISPLAY 1.021277 (-7650 575);
PAINT ORANGE (-7650 575);
FORCEPROP 0 LAST L3 LOCATION
J 0
(-7650 675);
DISPLAY 1.489362 (-7650 675);
PAINT AQUA (-7650 675);
FORCEPROP 2 LAST CDS_LIB mstr_symbols
J 0
(-8200 900);
PAINT ORANGE (-8200 900);
DISPLAY INVISIBLE (-8200 900);
FORCEPROP 2 LAST BOM_COST SB
J 0
(-8400 850);
DISPLAY 1.361702 (-8400 850);
PAINT ORANGE (-8400 850);
DISPLAY INVISIBLE (-8400 850);
FORCEPROP 1 LAST COMMENT_BODY TRUE
J 0
(-8175 1000);
DISPLAY 1.319149 (-8175 1000);
PAINT ORANGE (-8175 1000);
DISPLAY INVISIBLE (-8175 1000);
FORCEADD INTEL_CORP_BPAGE..1
(-800 -550);
FORCEPROP 1 LAST CDS_CON_LAST_MODIFIED Tue Dec 01 11:51:56 2015
J 0
(-2225 -225);
DISPLAY 1.340426 (-2225 -225);
PAINT ORANGE (-2225 -225);
DISPLAY INVISIBLE (-2225 -225);
FORCEPROP 1 LAST CUSTOM_TXT_CDS <CURRENT_DESIGN_SHEET> OF <TOTAL_DESIGN_SHEETS>
J 0
(-1300 -525);
PAINT GREEN (-1300 -525);
FORCEPROP 1 LAST CUSTOM_TXT_CDS <CON_LAST_MODIFIED>
J 0
(-2725 -200);
PAINT GREEN (-2725 -200);
FORCEPROP 2 LAST CUSTOM_TXT_CDS <XR_PAGE_TITLE>
J 0
(-8690 4700);
DISPLAY 0.638298 (-8690 4700);
PAINT PINK (-8690 4700);
DISPLAY INVISIBLE (-8690 4700);
FORCEPROP 1 LAST SCH_ADDRESS3 Santa Clara, CA 95052-8119
J 0
(-4775 -525);
DISPLAY 0.617021 (-4775 -525);
PAINT YELLOW (-4775 -525);
FORCEPROP 1 LAST SCH_ADDRESS2 P.O. BOX 58119
J 0
(-4775 -475);
DISPLAY 0.617021 (-4775 -475);
PAINT YELLOW (-4775 -475);
FORCEPROP 1 LAST SCH_ADDRESS1 2200 Mission College Blvd.
J 0
(-4775 -425);
DISPLAY 0.617021 (-4775 -425);
PAINT YELLOW (-4775 -425);
FORCEPROP 1 LAST SCH_TITLE LEWISBURG 2/11 USB
J 0
(-8750 -500);
DISPLAY 1.212766 (-8750 -500);
PAINT YELLOW (-8750 -500);
FORCEPROP 1 LAST SCH_REV 2.420
J 0
(-1050 -400);
DISPLAY 0.978723 (-1050 -400);
PAINT YELLOW (-1050 -400);
FORCEPROP 1 LAST SCH_DEPT BESD
J 1
(-5250 -450);
DISPLAY 1.212766 (-5250 -450);
PAINT YELLOW (-5250 -450);
FORCEPROP 1 LAST SCH_NUMBER H4694802
J 0
(-2100 -400);
DISPLAY 1.212766 (-2100 -400);
PAINT YELLOW (-2100 -400);
FORCEPROP 2 LAST CDS_LIB mstr_symbols
J 0
(-800 -550);
PAINT ORANGE (-800 -550);
DISPLAY INVISIBLE (-800 -550);
FORCEPROP 2 LAST PAGE_BORDER TRUE
J 0
(-8690 4700);
DISPLAY 0.851064 (-8690 4700);
PAINT PINK (-8690 4700);
DISPLAY INVISIBLE (-8690 4700);
FORCEPROP 1 LAST COMMENT_BODY TRUE
J 0
(-788 -538);
DISPLAY 0.638298 (-788 -538);
PAINT PEACH (-788 -538);
DISPLAY INVISIBLE (-788 -538);
FORCEPROP 2 LAST CDS_XR_PAGE_TITLE CR-115 : @BASEBOARD_FAB2_LIB.BASEBOARD_FAB2(SCH_1):PAGE115
J 0
(-8690 4700);
DISPLAY 0.638298 (-8690 4700);
PAINT PINK (-8690 4700);
DISPLAY INVISIBLE (-8690 4700);
WIRE 16 -1 (-5425 1675)(-5425 1600);
WIRE 16 -1 (-5750 1675)(-5750 1600);
WIRE 16 -1 (-2275 1700)(-3250 1700);
FORCEPROP 0 LAST SIG_NAME TP_USB2_P03_DN
J 0
(-2650 1710);
DISPLAY 0.617021 (-2650 1710);
PAINT ORANGE (-2650 1710);
FORCEPROP 2 LASTPROP $XRERR UNIQUE?
J 0
(-2245 1700);
DISPLAY 0.638298 (-2245 1700);
PAINT MONO (-2245 1700);
DISPLAY INVISIBLE (-2245 1700);
WIRE 16 -1 (-2225 1650)(-3250 1650);
FORCEPROP 0 LAST SIG_NAME USB2_P02_DP
J 0
(-2650 1660);
DISPLAY 0.617021 (-2650 1660);
PAINT ORANGE (-2650 1660);
WIRE 16 -1 (-2225 1600)(-3250 1600);
FORCEPROP 0 LAST SIG_NAME USB2_P02_DN
J 0
(-2650 1610);
DISPLAY 0.617021 (-2650 1610);
PAINT ORANGE (-2650 1610);
WIRE 16 -1 (-2225 1500)(-3250 1500);
FORCEPROP 0 LAST SIG_NAME USB2_P01_DN
J 0
(-2650 1510);
DISPLAY 0.617021 (-2650 1510);
PAINT ORANGE (-2650 1510);
WIRE 16 -1 (-2225 1550)(-3250 1550);
FORCEPROP 0 LAST SIG_NAME USB2_P01_DP
J 0
(-2650 1560);
DISPLAY 0.617021 (-2650 1560);
PAINT ORANGE (-2650 1560);
WIRE 16 -1 (-5050 450)(-5050 550);
WIRE 16 -1 (-5050 350)(-5050 450);
WIRE 16 -1 (-5050 450)(-8425 450);
WIRE 16 -1 (-5050 550)(-5050 650);
WIRE 16 -1 (-8425 550)(-5050 550);
WIRE 16 -1 (-8425 450)(-8425 550);
WIRE 16 -1 (-8425 650)(-8425 550);
WIRE 16 -1 (-5050 650)(-5050 750);
WIRE 16 -1 (-8425 650)(-5050 650);
WIRE 16 -1 (-8425 450)(-8425 350);
WIRE 16 -1 (-5775 350)(-5050 350);
WIRE 16 -1 (-5775 750)(-5775 350);
WIRE 16 -1 (-6175 350)(-5775 350);
WIRE 16 -1 (-8425 350)(-7700 350);
WIRE 16 -1 (-8425 750)(-8425 650);
WIRE 16 -1 (-5050 750)(-5775 750);
WIRE 16 -1 (-5775 750)(-6175 750);
WIRE 16 -1 (-7700 750)(-8425 750);
WIRE 16 -1 (-7700 350)(-6600 350);
WIRE 16 -1 (-7700 750)(-7700 350);
WIRE 16 -1 (-6175 750)(-6175 350);
WIRE 16 -1 (-6600 350)(-6175 350);
WIRE 16 -1 (-6600 750)(-6600 350);
WIRE 16 -1 (-6175 750)(-6600 750);
WIRE 16 -1 (-6600 750)(-7700 750);
WIRE 16 -1 (-2275 2500)(-3250 2500);
FORCEPROP 0 LAST SIG_NAME TP_USB2_P11_DN
J 0
(-2650 2510);
DISPLAY 0.617021 (-2650 2510);
PAINT ORANGE (-2650 2510);
FORCEPROP 2 LASTPROP $XRERR UNIQUE?
J 0
(-2245 2500);
DISPLAY 0.638298 (-2245 2500);
PAINT MONO (-2245 2500);
DISPLAY INVISIBLE (-2245 2500);
WIRE 16 -1 (-6250 3500)(-4750 3500);
FORCEPROP 0 LAST SIG_NAME TP_USB3_P06_RXP
J 0
(-6250 3510);
DISPLAY 0.617021 (-6250 3510);
PAINT ORANGE (-6250 3510);
FORCEPROP 2 LASTPROP $XRERR UNIQUE?
J 0
(-6490 3500);
DISPLAY 0.638298 (-6490 3500);
PAINT MONO (-6490 3500);
DISPLAY INVISIBLE (-6490 3500);
WIRE 16 -1 (-6250 3450)(-4750 3450);
FORCEPROP 0 LAST SIG_NAME TP_USB3_P06_RXN
J 0
(-6250 3460);
DISPLAY 0.617021 (-6250 3460);
PAINT ORANGE (-6250 3460);
FORCEPROP 2 LASTPROP $XRERR UNIQUE?
J 0
(-6490 3450);
DISPLAY 0.638298 (-6490 3450);
PAINT MONO (-6490 3450);
DISPLAY INVISIBLE (-6490 3450);
WIRE 16 -1 (-6250 3050)(-4750 3050);
FORCEPROP 0 LAST SIG_NAME TP_USB3_P02_RXN
J 0
(-6250 3060);
DISPLAY 0.617021 (-6250 3060);
PAINT ORANGE (-6250 3060);
FORCEPROP 2 LASTPROP $XRERR UNIQUE?
J 0
(-6490 3050);
DISPLAY 0.638298 (-6490 3050);
PAINT MONO (-6490 3050);
DISPLAY INVISIBLE (-6490 3050);
WIRE 16 -1 (-6250 3100)(-4750 3100);
FORCEPROP 0 LAST SIG_NAME TP_USB3_P02_RXP
J 0
(-6250 3110);
DISPLAY 0.617021 (-6250 3110);
PAINT ORANGE (-6250 3110);
FORCEPROP 2 LASTPROP $XRERR UNIQUE?
J 0
(-6490 3100);
DISPLAY 0.638298 (-6490 3100);
PAINT MONO (-6490 3100);
DISPLAY INVISIBLE (-6490 3100);
WIRE 16 -1 (-6250 3150)(-4750 3150);
FORCEPROP 0 LAST SIG_NAME TP_USB3_P03_RXN
J 0
(-6250 3160);
DISPLAY 0.617021 (-6250 3160);
PAINT ORANGE (-6250 3160);
FORCEPROP 2 LASTPROP $XRERR UNIQUE?
J 0
(-6490 3150);
DISPLAY 0.638298 (-6490 3150);
PAINT MONO (-6490 3150);
DISPLAY INVISIBLE (-6490 3150);
WIRE 16 -1 (-6250 3200)(-4750 3200);
FORCEPROP 0 LAST SIG_NAME TP_USB3_P03_RXP
J 0
(-6250 3210);
DISPLAY 0.617021 (-6250 3210);
PAINT ORANGE (-6250 3210);
FORCEPROP 2 LASTPROP $XRERR UNIQUE?
J 0
(-6490 3200);
DISPLAY 0.638298 (-6490 3200);
PAINT MONO (-6490 3200);
DISPLAY INVISIBLE (-6490 3200);
WIRE 16 -1 (-6250 3250)(-4750 3250);
FORCEPROP 0 LAST SIG_NAME TP_USB3_P04_RXN
J 0
(-6250 3260);
DISPLAY 0.617021 (-6250 3260);
PAINT ORANGE (-6250 3260);
FORCEPROP 2 LASTPROP $XRERR UNIQUE?
J 0
(-6490 3250);
DISPLAY 0.638298 (-6490 3250);
PAINT MONO (-6490 3250);
DISPLAY INVISIBLE (-6490 3250);
WIRE 16 -1 (-6250 3300)(-4750 3300);
FORCEPROP 0 LAST SIG_NAME TP_USB3_P04_RXP
J 0
(-6250 3310);
DISPLAY 0.617021 (-6250 3310);
PAINT ORANGE (-6250 3310);
FORCEPROP 2 LASTPROP $XRERR UNIQUE?
J 0
(-6490 3300);
DISPLAY 0.638298 (-6490 3300);
PAINT MONO (-6490 3300);
DISPLAY INVISIBLE (-6490 3300);
WIRE 16 -1 (-6250 3350)(-4750 3350);
FORCEPROP 0 LAST SIG_NAME TP_USB3_P05_RXN
J 0
(-6250 3360);
DISPLAY 0.617021 (-6250 3360);
PAINT ORANGE (-6250 3360);
FORCEPROP 2 LASTPROP $XRERR UNIQUE?
J 0
(-6490 3350);
DISPLAY 0.638298 (-6490 3350);
PAINT MONO (-6490 3350);
DISPLAY INVISIBLE (-6490 3350);
WIRE 16 -1 (-6250 3400)(-4750 3400);
FORCEPROP 0 LAST SIG_NAME TP_USB3_P05_RXP
J 0
(-6250 3410);
DISPLAY 0.617021 (-6250 3410);
PAINT ORANGE (-6250 3410);
FORCEPROP 2 LASTPROP $XRERR UNIQUE?
J 0
(-6490 3400);
DISPLAY 0.638298 (-6490 3400);
PAINT MONO (-6490 3400);
DISPLAY INVISIBLE (-6490 3400);
WIRE 16 -1 (-6250 2950)(-4750 2950);
FORCEPROP 0 LAST SIG_NAME USB3_P01_RXN
J 0
(-6250 2960);
DISPLAY 0.617021 (-6250 2960);
PAINT ORANGE (-6250 2960);
WIRE 16 -1 (-6250 3000)(-4750 3000);
FORCEPROP 0 LAST SIG_NAME USB3_P01_RXP
J 0
(-6250 3010);
DISPLAY 0.617021 (-6250 3010);
PAINT ORANGE (-6250 3010);
WIRE 16 -1 (-4750 1950)(-5425 1950);
FORCEPROP 2 LAST SIG_NAME A_USB2_VBUS
J 0
(-5220 1960);
DISPLAY 0.617021 (-5220 1960);
PAINT ORANGE (-5220 1960);
FORCEPROP 2 LASTPROP $XRERR UNIQUE?
J 0
(-5460 1960);
DISPLAY 0.638298 (-5460 1960);
PAINT MONO (-5460 1960);
DISPLAY INVISIBLE (-5460 1960);
WIRE 16 -1 (-5425 1875)(-5425 1950);
WIRE 16 -1 (-5225 2050)(-4750 2050);
FORCEPROP 2 LAST SIG_NAME TP_PCH_RSVD55
J 0
(-5235 2060);
DISPLAY 0.617021 (-5235 2060);
PAINT ORANGE (-5235 2060);
FORCEPROP 2 LASTPROP $XRERR UNIQUE?
J 0
(-5465 2050);
DISPLAY 0.638298 (-5465 2050);
PAINT MONO (-5465 2050);
DISPLAY INVISIBLE (-5465 2050);
WIRE 16 -1 (-5750 2150)(-4750 2150);
FORCEPROP 0 LAST SIG_NAME A_USB2_COMP
J 0
(-5360 2160);
DISPLAY 0.617021 (-5360 2160);
PAINT ORANGE (-5360 2160);
FORCEPROP 2 LASTPROP $XRERR UNIQUE?
J 0
(-5600 2160);
DISPLAY 0.638298 (-5600 2160);
PAINT MONO (-5600 2160);
DISPLAY INVISIBLE (-5600 2160);
WIRE 16 -1 (-5750 1875)(-5750 2150);
WIRE 16 -1 (-2275 2000)(-3250 2000);
FORCEPROP 0 LAST SIG_NAME TP_USB2_P06_DN
J 0
(-2650 2010);
DISPLAY 0.617021 (-2650 2010);
PAINT ORANGE (-2650 2010);
FORCEPROP 2 LASTPROP $XRERR UNIQUE?
J 0
(-2245 2000);
DISPLAY 0.638298 (-2245 2000);
PAINT MONO (-2245 2000);
DISPLAY INVISIBLE (-2245 2000);
WIRE 16 -1 (-2275 1750)(-3250 1750);
FORCEPROP 0 LAST SIG_NAME TP_USB2_P03_DP
J 0
(-2650 1760);
DISPLAY 0.617021 (-2650 1760);
PAINT ORANGE (-2650 1760);
FORCEPROP 2 LASTPROP $XRERR UNIQUE?
J 0
(-2245 1750);
DISPLAY 0.638298 (-2245 1750);
PAINT MONO (-2245 1750);
DISPLAY INVISIBLE (-2245 1750);
WIRE 16 -1 (-2225 1850)(-3250 1850);
FORCEPROP 0 LAST SIG_NAME USB_PCH_BMC_P4_DP
J 0
(-2650 1860);
DISPLAY 0.617021 (-2650 1860);
PAINT ORANGE (-2650 1860);
WIRE 16 -1 (-2225 1800)(-3250 1800);
FORCEPROP 0 LAST SIG_NAME USB_PCH_BMC_P4_DN
J 0
(-2650 1810);
DISPLAY 0.617021 (-2650 1810);
PAINT ORANGE (-2650 1810);
WIRE 16 -1 (-2225 1900)(-3250 1900);
FORCEPROP 0 LAST SIG_NAME USB2_PCH_BMC_P5_DN
J 0
(-2650 1910);
DISPLAY 0.617021 (-2650 1910);
PAINT ORANGE (-2650 1910);
WIRE 16 -1 (-2225 1950)(-3250 1950);
FORCEPROP 0 LAST SIG_NAME USB2_PCH_BMC_P5_DP
J 0
(-2650 1960);
DISPLAY 0.617021 (-2650 1960);
PAINT ORANGE (-2650 1960);
WIRE 16 -1 (-2275 2400)(-3250 2400);
FORCEPROP 0 LAST SIG_NAME TP_USB2_P10_DN
J 0
(-2650 2410);
DISPLAY 0.617021 (-2650 2410);
PAINT ORANGE (-2650 2410);
FORCEPROP 2 LASTPROP $XRERR UNIQUE?
J 0
(-2245 2400);
DISPLAY 0.638298 (-2245 2400);
PAINT MONO (-2245 2400);
DISPLAY INVISIBLE (-2245 2400);
WIRE 16 -1 (-2275 2600)(-3250 2600);
FORCEPROP 0 LAST SIG_NAME TP_USB2_P12_DN
J 0
(-2650 2610);
DISPLAY 0.617021 (-2650 2610);
PAINT ORANGE (-2650 2610);
FORCEPROP 2 LASTPROP $XRERR UNIQUE?
J 0
(-2245 2600);
DISPLAY 0.638298 (-2245 2600);
PAINT MONO (-2245 2600);
DISPLAY INVISIBLE (-2245 2600);
WIRE 16 -1 (-2275 2700)(-3250 2700);
FORCEPROP 0 LAST SIG_NAME TP_USB2_P13_DN
J 0
(-2650 2710);
DISPLAY 0.617021 (-2650 2710);
PAINT ORANGE (-2650 2710);
FORCEPROP 2 LASTPROP $XRERR UNIQUE?
J 0
(-2245 2700);
DISPLAY 0.638298 (-2245 2700);
PAINT MONO (-2245 2700);
DISPLAY INVISIBLE (-2245 2700);
WIRE 16 -1 (-2275 2800)(-3250 2800);
FORCEPROP 0 LAST SIG_NAME TP_USB2_P14_DN
J 0
(-2650 2810);
DISPLAY 0.617021 (-2650 2810);
PAINT ORANGE (-2650 2810);
FORCEPROP 2 LASTPROP $XRERR UNIQUE?
J 0
(-2245 2800);
DISPLAY 0.638298 (-2245 2800);
PAINT MONO (-2245 2800);
DISPLAY INVISIBLE (-2245 2800);
WIRE 16 -1 (-2275 2100)(-3250 2100);
FORCEPROP 0 LAST SIG_NAME TP_USB2_P07_DN
J 0
(-2650 2110);
DISPLAY 0.617021 (-2650 2110);
PAINT ORANGE (-2650 2110);
FORCEPROP 2 LASTPROP $XRERR UNIQUE?
J 0
(-2245 2100);
DISPLAY 0.638298 (-2245 2100);
PAINT MONO (-2245 2100);
DISPLAY INVISIBLE (-2245 2100);
WIRE 16 -1 (-2275 2200)(-3250 2200);
FORCEPROP 0 LAST SIG_NAME TP_USB2_P8_DN
J 0
(-2650 2210);
DISPLAY 0.617021 (-2650 2210);
PAINT ORANGE (-2650 2210);
FORCEPROP 2 LASTPROP $XRERR UNIQUE?
J 0
(-2245 2200);
DISPLAY 0.638298 (-2245 2200);
PAINT MONO (-2245 2200);
DISPLAY INVISIBLE (-2245 2200);
WIRE 16 -1 (-2275 2300)(-3250 2300);
FORCEPROP 0 LAST SIG_NAME TP_USB2_P9_DN
J 0
(-2650 2310);
DISPLAY 0.617021 (-2650 2310);
PAINT ORANGE (-2650 2310);
FORCEPROP 2 LASTPROP $XRERR UNIQUE?
J 0
(-2245 2300);
DISPLAY 0.638298 (-2245 2300);
PAINT MONO (-2245 2300);
DISPLAY INVISIBLE (-2245 2300);
WIRE 16 -1 (-2275 2450)(-3250 2450);
FORCEPROP 0 LAST SIG_NAME TP_USB2_P10_DP
J 0
(-2650 2460);
DISPLAY 0.617021 (-2650 2460);
PAINT ORANGE (-2650 2460);
FORCEPROP 2 LASTPROP $XRERR UNIQUE?
J 0
(-2245 2450);
DISPLAY 0.638298 (-2245 2450);
PAINT MONO (-2245 2450);
DISPLAY INVISIBLE (-2245 2450);
WIRE 16 -1 (-2275 2550)(-3250 2550);
FORCEPROP 0 LAST SIG_NAME TP_USB2_P11_DP
J 0
(-2650 2560);
DISPLAY 0.617021 (-2650 2560);
PAINT ORANGE (-2650 2560);
FORCEPROP 2 LASTPROP $XRERR UNIQUE?
J 0
(-2245 2550);
DISPLAY 0.638298 (-2245 2550);
PAINT MONO (-2245 2550);
DISPLAY INVISIBLE (-2245 2550);
WIRE 16 -1 (-2275 2650)(-3250 2650);
FORCEPROP 0 LAST SIG_NAME TP_USB2_P12_DP
J 0
(-2650 2660);
DISPLAY 0.617021 (-2650 2660);
PAINT ORANGE (-2650 2660);
FORCEPROP 2 LASTPROP $XRERR UNIQUE?
J 0
(-2245 2650);
DISPLAY 0.638298 (-2245 2650);
PAINT MONO (-2245 2650);
DISPLAY INVISIBLE (-2245 2650);
WIRE 16 -1 (-2275 2750)(-3250 2750);
FORCEPROP 0 LAST SIG_NAME TP_USB2_P13_DP
J 0
(-2650 2760);
DISPLAY 0.617021 (-2650 2760);
PAINT ORANGE (-2650 2760);
FORCEPROP 2 LASTPROP $XRERR UNIQUE?
J 0
(-2245 2750);
DISPLAY 0.638298 (-2245 2750);
PAINT MONO (-2245 2750);
DISPLAY INVISIBLE (-2245 2750);
WIRE 16 -1 (-2275 2850)(-3250 2850);
FORCEPROP 0 LAST SIG_NAME TP_USB2_P14_DP
J 0
(-2650 2860);
DISPLAY 0.617021 (-2650 2860);
PAINT ORANGE (-2650 2860);
FORCEPROP 2 LASTPROP $XRERR UNIQUE?
J 0
(-2245 2850);
DISPLAY 0.638298 (-2245 2850);
PAINT MONO (-2245 2850);
DISPLAY INVISIBLE (-2245 2850);
WIRE 16 -1 (-2275 2050)(-3250 2050);
FORCEPROP 0 LAST SIG_NAME TP_USB2_P06_DP
J 0
(-2650 2060);
DISPLAY 0.617021 (-2650 2060);
PAINT ORANGE (-2650 2060);
FORCEPROP 2 LASTPROP $XRERR UNIQUE?
J 0
(-2245 2050);
DISPLAY 0.638298 (-2245 2050);
PAINT MONO (-2245 2050);
DISPLAY INVISIBLE (-2245 2050);
WIRE 16 -1 (-2275 2150)(-3250 2150);
FORCEPROP 0 LAST SIG_NAME TP_USB2_P07_DP
J 0
(-2650 2160);
DISPLAY 0.617021 (-2650 2160);
PAINT ORANGE (-2650 2160);
FORCEPROP 2 LASTPROP $XRERR UNIQUE?
J 0
(-2245 2150);
DISPLAY 0.638298 (-2245 2150);
PAINT MONO (-2245 2150);
DISPLAY INVISIBLE (-2245 2150);
WIRE 16 -1 (-2275 2250)(-3250 2250);
FORCEPROP 0 LAST SIG_NAME TP_USB2_P8_DP
J 0
(-2650 2260);
DISPLAY 0.617021 (-2650 2260);
PAINT ORANGE (-2650 2260);
FORCEPROP 2 LASTPROP $XRERR UNIQUE?
J 0
(-2245 2250);
DISPLAY 0.638298 (-2245 2250);
PAINT MONO (-2245 2250);
DISPLAY INVISIBLE (-2245 2250);
WIRE 16 -1 (-2275 2350)(-3250 2350);
FORCEPROP 0 LAST SIG_NAME TP_USB2_P9_DP
J 0
(-2650 2360);
DISPLAY 0.617021 (-2650 2360);
PAINT ORANGE (-2650 2360);
FORCEPROP 2 LASTPROP $XRERR UNIQUE?
J 0
(-2245 2350);
DISPLAY 0.638298 (-2245 2350);
PAINT MONO (-2245 2350);
DISPLAY INVISIBLE (-2245 2350);
WIRE 16 -1 (-2275 3050)(-3250 3050);
FORCEPROP 0 LAST SIG_NAME TP_USB3_P02_TXN
J 0
(-2650 3060);
DISPLAY 0.617021 (-2650 3060);
PAINT ORANGE (-2650 3060);
FORCEPROP 2 LASTPROP $XRERR UNIQUE?
J 0
(-2245 3050);
DISPLAY 0.638298 (-2245 3050);
PAINT MONO (-2245 3050);
DISPLAY INVISIBLE (-2245 3050);
WIRE 16 -1 (-2275 3100)(-3250 3100);
FORCEPROP 0 LAST SIG_NAME TP_USB3_P02_TXP
J 0
(-2650 3110);
DISPLAY 0.617021 (-2650 3110);
PAINT ORANGE (-2650 3110);
FORCEPROP 2 LASTPROP $XRERR UNIQUE?
J 0
(-2245 3100);
DISPLAY 0.638298 (-2245 3100);
PAINT MONO (-2245 3100);
DISPLAY INVISIBLE (-2245 3100);
WIRE 16 -1 (-2275 3150)(-3250 3150);
FORCEPROP 0 LAST SIG_NAME TP_USB3_P03_TXN
J 0
(-2650 3160);
DISPLAY 0.617021 (-2650 3160);
PAINT ORANGE (-2650 3160);
FORCEPROP 2 LASTPROP $XRERR UNIQUE?
J 0
(-2245 3150);
DISPLAY 0.638298 (-2245 3150);
PAINT MONO (-2245 3150);
DISPLAY INVISIBLE (-2245 3150);
WIRE 16 -1 (-2275 3200)(-3250 3200);
FORCEPROP 0 LAST SIG_NAME TP_USB3_P03_TXP
J 0
(-2650 3210);
DISPLAY 0.617021 (-2650 3210);
PAINT ORANGE (-2650 3210);
FORCEPROP 2 LASTPROP $XRERR UNIQUE?
J 0
(-2245 3200);
DISPLAY 0.638298 (-2245 3200);
PAINT MONO (-2245 3200);
DISPLAY INVISIBLE (-2245 3200);
WIRE 16 -1 (-2275 3250)(-3250 3250);
FORCEPROP 0 LAST SIG_NAME TP_USB3_P04_TXN
J 0
(-2650 3260);
DISPLAY 0.617021 (-2650 3260);
PAINT ORANGE (-2650 3260);
FORCEPROP 2 LASTPROP $XRERR UNIQUE?
J 0
(-2245 3250);
DISPLAY 0.638298 (-2245 3250);
PAINT MONO (-2245 3250);
DISPLAY INVISIBLE (-2245 3250);
WIRE 16 -1 (-2275 3300)(-3250 3300);
FORCEPROP 0 LAST SIG_NAME TP_USB3_P04_TXP
J 0
(-2650 3310);
DISPLAY 0.617021 (-2650 3310);
PAINT ORANGE (-2650 3310);
FORCEPROP 2 LASTPROP $XRERR UNIQUE?
J 0
(-2245 3300);
DISPLAY 0.638298 (-2245 3300);
PAINT MONO (-2245 3300);
DISPLAY INVISIBLE (-2245 3300);
WIRE 16 -1 (-2275 3350)(-3250 3350);
FORCEPROP 0 LAST SIG_NAME TP_USB3_P05_TXN
J 0
(-2650 3360);
DISPLAY 0.617021 (-2650 3360);
PAINT ORANGE (-2650 3360);
FORCEPROP 2 LASTPROP $XRERR UNIQUE?
J 0
(-2245 3350);
DISPLAY 0.638298 (-2245 3350);
PAINT MONO (-2245 3350);
DISPLAY INVISIBLE (-2245 3350);
WIRE 16 -1 (-2275 3400)(-3250 3400);
FORCEPROP 0 LAST SIG_NAME TP_USB3_P05_TXP
J 0
(-2650 3410);
DISPLAY 0.617021 (-2650 3410);
PAINT ORANGE (-2650 3410);
FORCEPROP 2 LASTPROP $XRERR UNIQUE?
J 0
(-2245 3400);
DISPLAY 0.638298 (-2245 3400);
PAINT MONO (-2245 3400);
DISPLAY INVISIBLE (-2245 3400);
WIRE 16 -1 (-2275 3450)(-3250 3450);
FORCEPROP 0 LAST SIG_NAME TP_USB3_P06_TXN
J 0
(-2650 3460);
DISPLAY 0.617021 (-2650 3460);
PAINT ORANGE (-2650 3460);
FORCEPROP 2 LASTPROP $XRERR UNIQUE?
J 0
(-2245 3450);
DISPLAY 0.638298 (-2245 3450);
PAINT MONO (-2245 3450);
DISPLAY INVISIBLE (-2245 3450);
WIRE 16 -1 (-2275 3500)(-3250 3500);
FORCEPROP 0 LAST SIG_NAME TP_USB3_P06_TXP
J 0
(-2650 3510);
DISPLAY 0.617021 (-2650 3510);
PAINT ORANGE (-2650 3510);
FORCEPROP 2 LASTPROP $XRERR UNIQUE?
J 0
(-2245 3500);
DISPLAY 0.638298 (-2245 3500);
PAINT MONO (-2245 3500);
DISPLAY INVISIBLE (-2245 3500);
WIRE 16 -1 (-2225 2950)(-3250 2950);
FORCEPROP 0 LAST SIG_NAME USB3_P01_TXN
J 0
(-2650 2960);
DISPLAY 0.617021 (-2650 2960);
PAINT ORANGE (-2650 2960);
WIRE 16 -1 (-2225 3000)(-3250 3000);
FORCEPROP 0 LAST SIG_NAME USB3_P01_TXP
J 0
(-2650 3010);
DISPLAY 0.617021 (-2650 3010);
PAINT ORANGE (-2650 3010);
DOT 1 (-7700 750);
DOT 1 (-6175 750);
DOT 1 (-5775 750);
DOT 1 (-5050 450);
DOT 1 (-5050 550);
DOT 1 (-5050 650);
DOT 1 (-8425 550);
DOT 1 (-8425 650);
DOT 1 (-8425 450);
DOT 1 (-6600 750);
DOT 1 (-6600 350);
DOT 1 (-5775 350);
DOT 1 (-6175 350);
DOT 1 (-7700 350);
FORCENOTE
ROOM=SB
(-8686 -415) 0;
DISPLAY LEFT (-8686 -415);
DISPLAY 0.808511 (-8686 -415);
PAINT PURPLE (-8686 -415);
QUIT
